# T6G (Grand Teton) — schematic netlist excerpt (pin names and nets, part order shuffled) for the footprints in the layout excerpt that follows; sources: Cadence DE-HDL packaged netlist, KiCad conversion of 04192023_DAF0TMB3IC0_F0TG_MB_C_brd_V02_OCP.brd

R649  Q_RES  4.7K 1% EMPTY  pkg 0402LF  page 362 : A = P3V3_AUX ; B = TP_P0V9_RETIMER_CPU0_PMALERT
PC3  Q_CAPP  270UF 16V 20% OSCON  pkg THLF  page 190 : A = SW_P3V3_AUX_FLT ; B = GND
D8000  Q_LED  IC  pkg SMLF  page 256 : A = LED_P12V_AUX_R1 ; C = GND

(kicad_pcb
	(version 20260206)
	(generator "pcbnew")
	(generator_version "10.0")
	(general
		(thickness 1.6)
		(legacy_teardrops no)
	)
	(paper "A4")
	(title_block
		(title "04192023_DAF0TMB3IC0_F0TG_MB_C_brd_V02_OCP.brd")
		(comment 1 "Grand Teton / footprints 3642-3644 of 8354")
	)
	(layers
		(0 "F.Cu" signal "TOP")
		(4 "In1.Cu" signal "GND")
		(6 "In2.Cu" signal "IN1")
		(8 "In3.Cu" signal "GND1")
		(10 "In4.Cu" signal "IN2")
		(12 "In5.Cu" signal "GND2")
		(14 "In6.Cu" signal "IN3")
		(16 "In7.Cu" signal "GND3")
		(18 "In8.Cu" signal "VCC")
		(20 "In9.Cu" signal "VCC1")
		(22 "In10.Cu" signal "GND4")
		(24 "In11.Cu" signal "IN4")
		(26 "In12.Cu" signal "GND5")
		(28 "In13.Cu" signal "IN5")
		(30 "In14.Cu" signal "GND6")
		(32 "In15.Cu" signal "IN6")
		(34 "In16.Cu" signal "GND7")
		(2 "B.Cu" signal "BOTTOM")
		(9 "F.Adhes" user "F.Adhesive")
		(11 "B.Adhes" user "B.Adhesive")
		(13 "F.Paste" user "Package Geometry/Pastemask Top")
		(15 "B.Paste" user "Package Geometry/Pastemask Bottom")
		(5 "F.SilkS" user "Ref Des/Silkscreen Top")
		(7 "B.SilkS" user "Ref Des/Silkscreen Bottom")
		(1 "F.Mask" user "Board Geometry/Soldermask Top")
		(3 "B.Mask" user "Board Geometry/Soldermask Bottom")
		(17 "Dwgs.User" user "User.Drawings")
		(19 "Cmts.User" user "User.Comments")
		(21 "Eco1.User" user "User.Eco1")
		(23 "Eco2.User" user "User.Eco2")
		(25 "Edge.Cuts" user "Board Geometry/Outline")
		(27 "Margin" user)
		(31 "F.CrtYd" user "Package Geometry/Place Bound Top")
		(29 "B.CrtYd" user "Package Geometry/Place Bound Bottom")
		(35 "F.Fab" user "Ref Des/Assembly Top")
		(33 "B.Fab" user "Ref Des/Assembly Bottom")
	)
	(footprint ""
		(layer "F.Cu")
		(at 360.710226 -62.0903 180)
		(property "Reference" "D8000"
			(at 4.256532 1.652524 0)
			(unlocked yes)
			(layer "F.SilkS")
			(effects
				(font
					(size 0.7874 0.5842)
					(thickness 0.1524)
				)
				(justify left)
			)
		)
		(property "Value" ""
			(at 0 0 180)
			(layer "F.Fab")
			(effects
				(font
					(size 1.27 1.27)
				)
			)
		)
		(duplicate_pad_numbers_are_jumpers no)
		(fp_line
			(start 1.16078 0.4826)
			(end -0.64008 0.4826)
			(stroke
				(width 0.1524)
				(type default)
			)
			(layer "F.SilkS")
		)
		(fp_line
			(start 1.16078 -0.4826)
			(end 1.16078 0.4826)
			(stroke
				(width 0.1524)
				(type default)
			)
			(layer "F.SilkS")
		)
		(fp_line
			(start 1.03378 0.4826)
			(end -0.79248 0.4826)
			(stroke
				(width 0.1524)
				(type default)
			)
			(layer "F.SilkS")
		)
		(fp_line
			(start 1.03378 -0.4826)
			(end 1.03378 0.4826)
			(stroke
				(width 0.1524)
				(type default)
			)
			(layer "F.SilkS")
		)
		(fp_line
			(start 0.90678 0.4826)
			(end -0.90678 0.4826)
			(stroke
				(width 0.1524)
				(type default)
			)
			(layer "F.SilkS")
		)
		(fp_line
			(start 0.90678 -0.4826)
			(end 0.90678 0.4826)
			(stroke
				(width 0.1524)
				(type default)
			)
			(layer "F.SilkS")
		)
		(fp_line
			(start -0.64008 -0.4826)
			(end 1.16078 -0.4826)
			(stroke
				(width 0.1524)
				(type default)
			)
			(layer "F.SilkS")
		)
		(fp_line
			(start -0.79248 -0.4826)
			(end 1.03378 -0.4826)
			(stroke
				(width 0.1524)
				(type default)
			)
			(layer "F.SilkS")
		)
		(fp_line
			(start -0.89408 -0.4826)
			(end 0.90678 -0.4826)
			(stroke
				(width 0.1524)
				(type default)
			)
			(layer "F.SilkS")
		)
		(fp_line
			(start -0.90678 0.4826)
			(end -0.90678 -0.4699)
			(stroke
				(width 0.1524)
				(type default)
			)
			(layer "F.SilkS")
		)
		(fp_line
			(start 0.499872 0.249936)
			(end -0.499872 0.249936)
			(stroke
				(width 0.1)
				(type default)
			)
			(layer "F.Fab")
		)
		(fp_line
			(start 0.499872 -0.249936)
			(end 0.499872 0.249936)
			(stroke
				(width 0.1)
				(type default)
			)
			(layer "F.Fab")
		)
		(fp_line
			(start -0.499872 0.249936)
			(end -0.499872 -0.249936)
			(stroke
				(width 0.1)
				(type default)
			)
			(layer "F.Fab")
		)
		(fp_line
			(start -0.499872 -0.249936)
			(end 0.499872 -0.249936)
			(stroke
				(width 0.1)
				(type default)
			)
			(layer "F.Fab")
		)
		(pad "A" smd rect
			(at -0.47498 0 180)
			(size 0.6096 0.7112)
			(layers "F.Cu" "F.Mask" "F.Paste")
			(net "LED_P12V_AUX_R1")
		)
		(pad "C" smd rect
			(at 0.47498 0 180)
			(size 0.6096 0.7112)
			(layers "F.Cu" "F.Mask" "F.Paste")
			(net "GND")
		)
	)
	(footprint ""
		(layer "F.Cu")
		(at 432.12639 -50.447448 180)
		(property "Reference" "PC3"
			(at -2.5908 -1.793748 0)
			(unlocked yes)
			(layer "F.SilkS")
			(effects
				(font
					(size 0.7874 0.5842)
					(thickness 0.1524)
				)
				(justify left)
			)
		)
		(property "Value" ""
			(at 0 0 180)
			(layer "F.Fab")
			(effects
				(font
					(size 1.27 1.27)
				)
			)
		)
		(duplicate_pad_numbers_are_jumpers no)
		(fp_line
			(start -3.400044 1.249934)
			(end 3.400044 1.249934)
			(stroke
				(width 0.1524)
				(type default)
			)
			(layer "F.SilkS")
		)
		(fp_circle
			(center 0 1.249934)
			(end -3.39979 1.249934)
			(stroke
				(width 0.1524)
				(type default)
			)
			(fill no)
			(layer "F.SilkS")
		)
		(fp_poly
			(pts
				(arc
					(start 3.400044 1.249934)
					(mid 0 4.649978)
					(end -3.400044 1.249934)
				)
			)
			(stroke
				(width 0)
				(type default)
			)
			(fill yes)
			(layer "F.SilkS")
		)
		(fp_circle
			(center 0 1.249934)
			(end -3.39979 1.249934)
			(stroke
				(width 0.1)
				(type default)
			)
			(fill no)
			(layer "F.Fab")
		)
		(pad "1" thru_hole rect
			(at 0 0 180)
			(size 1.524 1.524)
			(drill 1.016)
			(layers "*.Cu" "*.Mask")
			(remove_unused_layers no)
			(net "SW_P3V3_AUX_FLT")
			(clearance 0)
			(padstack
				(mode front_inner_back)
				(layer "Inner"
					(shape circle)
					(size 1.524 1.524)
					(clearance 0)
				)
				(layer "B.Cu"
					(shape rect)
					(size 1.524 1.524)
					(clearance 0)
				)
			)
		)
		(pad "2" thru_hole circle
			(at 0 2.500122 180)
			(size 1.524 1.524)
			(drill 1.016)
			(layers "*.Cu" "*.Mask")
			(remove_unused_layers no)
			(net "GND")
			(clearance 0)
		)
	)
	(footprint ""
		(layer "F.Cu")
		(at 440.807602 -429.37811 -90)
		(property "Reference" "R649"
			(at 0 0 270)
			(layer "F.SilkS")
			(hide yes)
			(effects
				(font
					(size 1.27 1.27)
				)
			)
		)
		(property "Value" ""
			(at 0 0 270)
			(layer "F.Fab")
			(effects
				(font
					(size 1.27 1.27)
				)
			)
		)
		(duplicate_pad_numbers_are_jumpers no)
		(fp_line
			(start -0.7874 0.4064)
			(end -0.7874 -0.4064)
			(stroke
				(width 0.1524)
				(type default)
			)
			(layer "F.SilkS")
		)
		(fp_line
			(start 0.7874 0.4064)
			(end -0.7874 0.4064)
			(stroke
				(width 0.1524)
				(type default)
			)
			(layer "F.SilkS")
		)
		(fp_line
			(start -0.7874 -0.4064)
			(end 0.7874 -0.4064)
			(stroke
				(width 0.1524)
				(type default)
			)
			(layer "F.SilkS")
		)
		(fp_line
			(start 0.7874 -0.4064)
			(end 0.7874 0.4064)
			(stroke
				(width 0.1524)
				(type default)
			)
			(layer "F.SilkS")
		)
		(fp_line
			(start -0.67945 0.3048)
			(end -0.67945 -0.305054)
			(stroke
				(width 0.1)
				(type default)
			)
			(layer "F.Fab")
		)
		(fp_line
			(start -0.12065 0.3048)
			(end -0.67945 0.3048)
			(stroke
				(width 0.1)
				(type default)
			)
			(layer "F.Fab")
		)
		(fp_line
			(start 0.120396 0.3048)
			(end 0.120396 0.2794)
			(stroke
				(width 0.1)
				(type default)
			)
			(layer "F.Fab")
		)
		(fp_line
			(start 0.67945 0.3048)
			(end 0.120396 0.3048)
			(stroke
				(width 0.1)
				(type default)
			)
			(layer "F.Fab")
		)
		(fp_line
			(start -0.12065 0.2794)
			(end -0.12065 0.3048)
			(stroke
				(width 0.1)
				(type default)
			)
			(layer "F.Fab")
		)
		(fp_line
			(start 0.120396 0.2794)
			(end -0.12065 0.2794)
			(stroke
				(width 0.1)
				(type default)
			)
			(layer "F.Fab")
		)
		(fp_line
			(start -0.12065 -0.2794)
			(end 0.12065 -0.2794)
			(stroke
				(width 0.1)
				(type default)
			)
			(layer "F.Fab")
		)
		(fp_line
			(start 0.12065 -0.2794)
			(end 0.12065 -0.3048)
			(stroke
				(width 0.1)
				(type default)
			)
			(layer "F.Fab")
		)
		(fp_line
			(start 0.12065 -0.3048)
			(end 0.67945 -0.3048)
			(stroke
				(width 0.1)
				(type default)
			)
			(layer "F.Fab")
		)
		(fp_line
			(start 0.67945 -0.3048)
			(end 0.67945 0.3048)
			(stroke
				(width 0.1)
				(type default)
			)
			(layer "F.Fab")
		)
		(fp_line
			(start -0.67945 -0.305054)
			(end -0.12065 -0.305054)
			(stroke
				(width 0.1)
				(type default)
			)
			(layer "F.Fab")
		)
		(fp_line
			(start -0.12065 -0.305054)
			(end -0.12065 -0.2794)
			(stroke
				(width 0.1)
				(type default)
			)
			(layer "F.Fab")
		)
		(pad "1" smd circle
			(at -0.40005 0 270)
			(size 0 0)
			(layers "F.Cu" "F.Mask" "F.Paste")
			(net "P3V3_AUX")
		)
		(pad "2" smd circle
			(at 0.40005 0 270)
			(size 0 0)
			(layers "F.Cu" "F.Mask" "F.Paste")
			(net "TP_P0V9_RETIMER_CPU0_PMALERT")
		)
	)
)
